(kicad_pcb
	(version 20260206)
	(generator "pcbnew")
	(generator_version "10.0")
	(general
		(thickness 1.6)
		(legacy_teardrops no)
	)
	(paper "A4")
	(title_block
		(title "Bryce Canyon_F.DPB_16315-1-OCP.brd")
		(comment 1 "Bryce Canyon / footprints 545-550 of 2223")
	)
	(layers
		(0 "F.Cu" signal "TOP")
		(4 "In1.Cu" signal "L2GND")
		(6 "In2.Cu" signal "L3")
		(8 "In3.Cu" signal "L4GND")
		(10 "In4.Cu" signal "L5")
		(12 "In5.Cu" signal "L6VCC")
		(14 "In6.Cu" signal "L7VCC")
		(16 "In7.Cu" signal "L8")
		(18 "In8.Cu" signal "L9GND")
		(20 "In9.Cu" signal "L10")
		(22 "In10.Cu" signal "L11GND")
		(2 "B.Cu" signal "BOTTOM")
		(9 "F.Adhes" user "F.Adhesive")
		(11 "B.Adhes" user "B.Adhesive")
		(13 "F.Paste" user "Package Geometry/Pastemask Top")
		(15 "B.Paste" user "Package Geometry/Pastemask Bottom")
		(5 "F.SilkS" user "Ref Des/Silkscreen Top")
		(7 "B.SilkS" user "Ref Des/Silkscreen Bottom")
		(1 "F.Mask" user "Board Geometry/Soldermask Top")
		(3 "B.Mask" user "Board Geometry/Soldermask Bottom")
		(17 "Dwgs.User" user "User.Drawings")
		(19 "Cmts.User" user "User.Comments")
		(21 "Eco1.User" user "User.Eco1")
		(23 "Eco2.User" user "User.Eco2")
		(25 "Edge.Cuts" user "Board Geometry/Outline")
		(27 "Margin" user)
		(31 "F.CrtYd" user "Package Geometry/Place Bound Top")
		(29 "B.CrtYd" user "Package Geometry/Place Bound Bottom")
		(35 "F.Fab" user "Ref Des/Assembly Top")
		(33 "B.Fab" user "Ref Des/Assembly Bottom")
	)
	(footprint ""
		(layer "F.Cu")
		(at 20.684998 -285.285942 180)
		(property "Reference" "Q215"
			(at 0 0 180)
			(layer "F.SilkS")
			(hide yes)
			(effects
				(font
					(size 1.27 1.27)
				)
			)
		)
		(property "Value" "AO4406AL-GP"
			(at -3.707384 -1.5367 180)
			(unlocked yes)
			(layer "F.Fab")
			(hide yes)
			(effects
				(font
					(size 1.016 1.016)
					(thickness 0.1524)
				)
			)
		)
		(property "Device Type" "SOIC8H69"
			(at -3.707384 -3.0607 180)
			(unlocked yes)
			(layer "F.Fab")
			(hide yes)
			(effects
				(font
					(size 1.016 1.016)
					(thickness 0.1524)
				)
			)
		)
		(duplicate_pad_numbers_are_jumpers no)
		(fp_line
			(start 2.1336 1.4224)
			(end 2.1336 -1.4224)
			(stroke
				(width 0.1524)
				(type default)
			)
			(layer "F.SilkS")
		)
		(fp_line
			(start 2.1336 -1.4224)
			(end -2.7432 -1.4224)
			(stroke
				(width 0.1524)
				(type default)
			)
			(layer "F.SilkS")
		)
		(fp_line
			(start -2.1844 -0.0508)
			(end -2.7178 0.508)
			(stroke
				(width 0.1524)
				(type default)
			)
			(layer "F.SilkS")
		)
		(fp_line
			(start -2.6289 3.4417)
			(end -2.6289 1.4732)
			(stroke
				(width 0.381)
				(type default)
			)
			(layer "F.SilkS")
		)
		(fp_line
			(start -2.7178 -0.508)
			(end -2.1844 -0.0508)
			(stroke
				(width 0.1524)
				(type default)
			)
			(layer "F.SilkS")
		)
		(fp_line
			(start -2.7432 1.4224)
			(end 2.1336 1.4224)
			(stroke
				(width 0.1524)
				(type default)
			)
			(layer "F.SilkS")
		)
		(fp_line
			(start -2.7432 1.4224)
			(end -2.6416 1.4224)
			(stroke
				(width 0.1524)
				(type default)
			)
			(layer "F.SilkS")
		)
		(fp_line
			(start -2.7432 -1.4224)
			(end -2.7432 1.4224)
			(stroke
				(width 0.1524)
				(type default)
			)
			(layer "F.SilkS")
		)
		(fp_poly
			(pts
				(xy -2.2098 -1.4224) (xy -2.2098 1.4224) (xy 2.2098 1.4224) (xy 2.2098 -1.4224)
			)
			(stroke
				(width 0)
				(type default)
			)
			(fill yes)
			(layer "F.SilkS")
		)
		(fp_rect
			(start -2.450084 2.999994)
			(end 2.450084 -2.999994)
			(stroke
				(width 0)
				(type default)
			)
			(fill no)
			(layer "F.CrtYd")
		)
		(fp_poly
			(pts
				(xy -2.8194 3.6322) (xy -2.8194 -3.6322) (xy 2.8194 -3.6322) (xy 2.8194 1.18364) (xy 2.450084 1.18364)
				(xy 2.450084 -2.999994) (xy -2.450084 -2.999994) (xy -2.450084 2.999994) (xy 2.450084 2.999994)
				(xy 2.450084 1.18618) (xy 2.8194 1.18618) (xy 2.8194 3.6322)
			)
			(stroke
				(width 0)
				(type default)
			)
			(fill no)
			(layer "F.CrtYd")
		)
		(fp_rect
			(start -2.8194 3.6322)
			(end 2.8194 -3.6322)
			(stroke
				(width 0)
				(type default)
			)
			(fill no)
			(layer "F.Fab")
		)
		(pad "1" smd rect
			(at -1.905 2.54 180)
			(size 0.635 1.651)
			(layers "F.Cu" "F.Mask" "F.Paste")
			(net "P5V_HDD0")
		)
		(pad "2" smd rect
			(at -0.635 2.54 180)
			(size 0.635 1.651)
			(layers "F.Cu" "F.Mask" "F.Paste")
			(net "P5V_HDD0")
		)
		(pad "3" smd rect
			(at 0.635 2.54 180)
			(size 0.635 1.651)
			(layers "F.Cu" "F.Mask" "F.Paste")
			(net "P5V_HDD0")
		)
		(pad "4" smd rect
			(at 1.905 2.54 180)
			(size 0.635 1.651)
			(layers "F.Cu" "F.Mask" "F.Paste")
			(net "SW_HDD_P0")
		)
		(pad "5" smd rect
			(at 1.905 -2.54 180)
			(size 0.635 1.651)
			(layers "F.Cu" "F.Mask" "F.Paste")
			(net "P5V_A_1")
		)
		(pad "6" smd rect
			(at 0.635 -2.54 180)
			(size 0.635 1.651)
			(layers "F.Cu" "F.Mask" "F.Paste")
			(net "P5V_A_1")
		)
		(pad "7" smd rect
			(at -0.635 -2.54 180)
			(size 0.635 1.651)
			(layers "F.Cu" "F.Mask" "F.Paste")
			(net "P5V_A_1")
		)
		(pad "8" smd rect
			(at -1.905 -2.54 180)
			(size 0.635 1.651)
			(layers "F.Cu" "F.Mask" "F.Paste")
			(net "P5V_A_1")
		)
	)
	(footprint ""
		(layer "F.Cu")
		(at 144.700498 -45.633894)
		(property "Reference" "R791"
			(at 0 0 0)
			(layer "F.SilkS")
			(hide yes)
			(effects
				(font
					(size 1.27 1.27)
				)
			)
		)
		(property "Value" "0R2J-2-GP"
			(at 0.064008 -3.993896 0)
			(unlocked yes)
			(layer "F.Fab")
			(hide yes)
			(effects
				(font
					(size 1.016 1.016)
					(thickness 0.1524)
				)
			)
		)
		(property "Device Type" "R402H16"
			(at 0.064008 -5.517896 0)
			(unlocked yes)
			(layer "F.Fab")
			(hide yes)
			(effects
				(font
					(size 1.016 1.016)
					(thickness 0.1524)
				)
			)
		)
		(duplicate_pad_numbers_are_jumpers no)
		(fp_line
			(start -0.508 -0.9398)
			(end -0.508 0.9398)
			(stroke
				(width 0.1524)
				(type default)
			)
			(layer "F.SilkS")
		)
		(fp_line
			(start 0.508 -0.9398)
			(end -0.508 -0.9398)
			(stroke
				(width 0.1524)
				(type default)
			)
			(layer "F.SilkS")
		)
		(fp_rect
			(start -0.508 0.9398)
			(end 0.508 -0.9398)
			(stroke
				(width 0)
				(type default)
			)
			(fill no)
			(layer "F.CrtYd")
		)
		(fp_rect
			(start -0.508 0.9398)
			(end 0.508 -0.9398)
			(stroke
				(width 0)
				(type default)
			)
			(fill no)
			(layer "F.Fab")
		)
		(pad "1" smd custom
			(at 0 -0.4445)
			(size 0.1397 0.1397)
			(layers "F.Cu" "F.Mask" "F.Paste")
			(net "SW_HDD_G28")
			(options
				(clearance outline)
				(anchor circle)
			)
			(primitives
				(gr_poly
					(pts
						(arc
							(start -0.1778 -0.2794)
							(mid -0.249642 -0.249642)
							(end -0.2794 -0.1778)
						)
						(arc
							(start -0.2794 0.1778)
							(mid -0.249642 0.249642)
							(end -0.1778 0.2794)
						)
						(arc
							(start 0.1778 0.2794)
							(mid 0.249642 0.249642)
							(end 0.2794 0.1778)
						)
						(arc
							(start 0.2794 -0.1778)
							(mid 0.249642 -0.249642)
							(end 0.1778 -0.2794)
						)
					)
					(width 0)
					(fill yes)
				)
			)
		)
		(pad "2" smd custom
			(at 0 0.4445)
			(size 0.1397 0.1397)
			(layers "F.Cu" "F.Mask" "F.Paste")
			(net "SW_HDD_R28")
			(options
				(clearance outline)
				(anchor circle)
			)
			(primitives
				(gr_poly
					(pts
						(arc
							(start -0.1778 -0.2794)
							(mid -0.249642 -0.249642)
							(end -0.2794 -0.1778)
						)
						(arc
							(start -0.2794 0.1778)
							(mid -0.249642 0.249642)
							(end -0.1778 0.2794)
						)
						(arc
							(start 0.1778 0.2794)
							(mid 0.249642 0.249642)
							(end 0.2794 0.1778)
						)
						(arc
							(start 0.2794 -0.1778)
							(mid 0.249642 -0.249642)
							(end 0.1778 -0.2794)
						)
					)
					(width 0)
					(fill yes)
				)
			)
		)
	)
	(footprint ""
		(layer "F.Cu")
		(at 443.848744 -245.278656 -90)
		(property "Reference" "R494"
			(at 0 0 270)
			(layer "F.SilkS")
			(hide yes)
			(effects
				(font
					(size 1.27 1.27)
				)
			)
		)
		(property "Value" "4K7R2J-2-GP"
			(at 0.064008 -3.993896 270)
			(unlocked yes)
			(layer "F.Fab")
			(hide yes)
			(effects
				(font
					(size 1.016 1.016)
					(thickness 0.1524)
				)
			)
		)
		(property "Device Type" "R402H16"
			(at 0.064008 -5.517896 270)
			(unlocked yes)
			(layer "F.Fab")
			(hide yes)
			(effects
				(font
					(size 1.016 1.016)
					(thickness 0.1524)
				)
			)
		)
		(duplicate_pad_numbers_are_jumpers no)
		(fp_line
			(start -0.508 -0.9398)
			(end -0.508 0.9398)
			(stroke
				(width 0.1524)
				(type default)
			)
			(layer "F.SilkS")
		)
		(fp_line
			(start 0.508 -0.9398)
			(end -0.508 -0.9398)
			(stroke
				(width 0.1524)
				(type default)
			)
			(layer "F.SilkS")
		)
		(fp_rect
			(start -0.508 0.9398)
			(end 0.508 -0.9398)
			(stroke
				(width 0)
				(type default)
			)
			(fill no)
			(layer "F.CrtYd")
		)
		(fp_rect
			(start -0.508 0.9398)
			(end 0.508 -0.9398)
			(stroke
				(width 0)
				(type default)
			)
			(fill no)
			(layer "F.Fab")
		)
		(pad "1" smd custom
			(at 0 -0.4445 270)
			(size 0.1397 0.1397)
			(layers "F.Cu" "F.Mask" "F.Paste")
			(net "DRIVE_A_10_ACT")
			(options
				(clearance outline)
				(anchor circle)
			)
			(primitives
				(gr_poly
					(pts
						(arc
							(start -0.1778 -0.2794)
							(mid -0.249642 -0.249642)
							(end -0.2794 -0.1778)
						)
						(arc
							(start -0.2794 0.1778)
							(mid -0.249642 0.249642)
							(end -0.1778 0.2794)
						)
						(arc
							(start 0.1778 0.2794)
							(mid 0.249642 0.249642)
							(end 0.2794 0.1778)
						)
						(arc
							(start 0.2794 -0.1778)
							(mid 0.249642 -0.249642)
							(end 0.1778 -0.2794)
						)
					)
					(width 0)
					(fill yes)
				)
			)
		)
		(pad "2" smd custom
			(at 0 0.4445 270)
			(size 0.1397 0.1397)
			(layers "F.Cu" "F.Mask" "F.Paste")
			(net "GND")
			(options
				(clearance outline)
				(anchor circle)
			)
			(primitives
				(gr_poly
					(pts
						(arc
							(start -0.1778 -0.2794)
							(mid -0.249642 -0.249642)
							(end -0.2794 -0.1778)
						)
						(arc
							(start -0.2794 0.1778)
							(mid -0.249642 0.249642)
							(end -0.1778 0.2794)
						)
						(arc
							(start 0.1778 0.2794)
							(mid 0.249642 0.249642)
							(end 0.2794 0.1778)
						)
						(arc
							(start 0.2794 -0.1778)
							(mid 0.249642 -0.249642)
							(end 0.1778 -0.2794)
						)
					)
					(width 0)
					(fill yes)
				)
			)
		)
	)
	(footprint ""
		(layer "F.Cu")
		(at 335.788 -275.735542 180)
		(property "Reference" "R285"
			(at 0 0 180)
			(layer "F.SilkS")
			(hide yes)
			(effects
				(font
					(size 1.27 1.27)
				)
			)
		)
		(property "Value" "0R2J-2-GP"
			(at 0.064008 -3.993896 180)
			(unlocked yes)
			(layer "F.Fab")
			(hide yes)
			(effects
				(font
					(size 1.016 1.016)
					(thickness 0.1524)
				)
			)
		)
		(property "Device Type" "R402H16"
			(at 0.064008 -5.517896 180)
			(unlocked yes)
			(layer "F.Fab")
			(hide yes)
			(effects
				(font
					(size 1.016 1.016)
					(thickness 0.1524)
				)
			)
		)
		(duplicate_pad_numbers_are_jumpers no)
		(fp_line
			(start 0.508 -0.9398)
			(end -0.508 -0.9398)
			(stroke
				(width 0.1524)
				(type default)
			)
			(layer "F.SilkS")
		)
		(fp_line
			(start -0.508 -0.9398)
			(end -0.508 0.9398)
			(stroke
				(width 0.1524)
				(type default)
			)
			(layer "F.SilkS")
		)
		(fp_rect
			(start -0.508 0.9398)
			(end 0.508 -0.9398)
			(stroke
				(width 0)
				(type default)
			)
			(fill no)
			(layer "F.CrtYd")
		)
		(fp_rect
			(start -0.508 0.9398)
			(end 0.508 -0.9398)
			(stroke
				(width 0)
				(type default)
			)
			(fill no)
			(layer "F.Fab")
		)
		(pad "1" smd custom
			(at 0 -0.4445 180)
			(size 0.1397 0.1397)
			(layers "F.Cu" "F.Mask" "F.Paste")
			(net "SW_HDD_G6")
			(options
				(clearance outline)
				(anchor circle)
			)
			(primitives
				(gr_poly
					(pts
						(arc
							(start -0.1778 -0.2794)
							(mid -0.249642 -0.249642)
							(end -0.2794 -0.1778)
						)
						(arc
							(start -0.2794 0.1778)
							(mid -0.249642 0.249642)
							(end -0.1778 0.2794)
						)
						(arc
							(start 0.1778 0.2794)
							(mid 0.249642 0.249642)
							(end 0.2794 0.1778)
						)
						(arc
							(start 0.2794 -0.1778)
							(mid 0.249642 -0.249642)
							(end 0.1778 -0.2794)
						)
					)
					(width 0)
					(fill yes)
				)
			)
		)
		(pad "2" smd custom
			(at 0 0.4445 180)
			(size 0.1397 0.1397)
			(layers "F.Cu" "F.Mask" "F.Paste")
			(net "SW_HDD_R6")
			(options
				(clearance outline)
				(anchor circle)
			)
			(primitives
				(gr_poly
					(pts
						(arc
							(start -0.1778 -0.2794)
							(mid -0.249642 -0.249642)
							(end -0.2794 -0.1778)
						)
						(arc
							(start -0.2794 0.1778)
							(mid -0.249642 0.249642)
							(end -0.1778 0.2794)
						)
						(arc
							(start 0.1778 0.2794)
							(mid 0.249642 0.249642)
							(end 0.2794 0.1778)
						)
						(arc
							(start 0.2794 -0.1778)
							(mid 0.249642 -0.249642)
							(end 0.1778 -0.2794)
						)
					)
					(width 0)
					(fill yes)
				)
			)
		)
	)
	(footprint ""
		(layer "F.Cu")
		(at 378.249942 -94.400116)
		(property "Reference" "FLED21"
			(at 0 0 0)
			(layer "F.SilkS")
			(hide yes)
			(effects
				(font
					(size 1.27 1.27)
				)
			)
		)
		(property "Value" "LED-BY-19-GP"
			(at -2.132076 1.414018 0)
			(unlocked yes)
			(layer "F.Fab")
			(hide yes)
			(effects
				(font
					(size 1.016 1.016)
					(thickness 0.1524)
				)
			)
		)
		(property "Device Type" "LED-1615-4PH26"
			(at -2.132076 -0.109982 0)
			(unlocked yes)
			(layer "F.Fab")
			(hide yes)
			(effects
				(font
					(size 1.016 1.016)
					(thickness 0.1524)
				)
			)
		)
		(duplicate_pad_numbers_are_jumpers no)
		(fp_line
			(start -1.2954 0.254)
			(end -1.2954 1.6002)
			(stroke
				(width 0.508)
				(type default)
			)
			(layer "F.SilkS")
		)
		(fp_line
			(start -1.2954 1.6002)
			(end 1.2954 1.6002)
			(stroke
				(width 0.508)
				(type default)
			)
			(layer "F.SilkS")
		)
		(fp_line
			(start -1.1176 -1.4224)
			(end 1.1176 -1.4224)
			(stroke
				(width 0.1524)
				(type default)
			)
			(layer "F.SilkS")
		)
		(fp_line
			(start -1.1176 1.4224)
			(end -1.1176 -1.4224)
			(stroke
				(width 0.1524)
				(type default)
			)
			(layer "F.SilkS")
		)
		(fp_line
			(start 1.1176 -1.4224)
			(end 1.1176 1.4224)
			(stroke
				(width 0.1524)
				(type default)
			)
			(layer "F.SilkS")
		)
		(fp_line
			(start 1.1176 1.4224)
			(end -1.1176 1.4224)
			(stroke
				(width 0.1524)
				(type default)
			)
			(layer "F.SilkS")
		)
		(fp_line
			(start 1.2954 1.6002)
			(end 1.2954 0.254)
			(stroke
				(width 0.508)
				(type default)
			)
			(layer "F.SilkS")
		)
		(fp_rect
			(start -0.7493 0.8001)
			(end 0.7493 -0.8001)
			(stroke
				(width 0)
				(type default)
			)
			(fill no)
			(layer "F.CrtYd")
		)
		(fp_poly
			(pts
				(xy -1.3716 1.6764) (xy -1.3716 -1.6764) (xy 1.3716 -1.6764) (xy 1.3716 0.0635) (xy 0.7493 0.0635)
				(xy 0.7493 -0.8001) (xy -0.7493 -0.8001) (xy -0.7493 0.8001) (xy 0.7493 0.8001) (xy 0.7493 0.0762)
				(xy 1.3716 0.0762) (xy 1.3716 1.6764)
			)
			(stroke
				(width 0)
				(type default)
			)
			(fill no)
			(layer "F.CrtYd")
		)
		(fp_rect
			(start -1.3716 1.6764)
			(end 1.3716 -1.6764)
			(stroke
				(width 0)
				(type default)
			)
			(fill no)
			(layer "F.Fab")
		)
		(pad "1" smd rect
			(at 0.50038 -0.73025)
			(size 0.7112 0.8636)
			(layers "F.Cu" "F.Mask" "F.Paste")
			(net "DRV_ACT_20")
		)
		(pad "2" smd rect
			(at -0.50038 -0.73025)
			(size 0.7112 0.8636)
			(layers "F.Cu" "F.Mask" "F.Paste")
			(net "FLT_HDD20")
		)
		(pad "3" smd rect
			(at 0.50038 0.73025)
			(size 0.7112 0.8636)
			(layers "F.Cu" "F.Mask" "F.Paste")
			(net "DRV_ACT_20_N")
		)
		(pad "4" smd rect
			(at -0.50038 0.73025)
			(size 0.7112 0.8636)
			(layers "F.Cu" "F.Mask" "F.Paste")
			(net "FLT_HDD20_N")
		)
	)
	(footprint ""
		(layer "F.Cu")
		(at 377.594876 -242.25377)
		(property "Reference" "R247"
			(at 0 0 0)
			(layer "F.SilkS")
			(hide yes)
			(effects
				(font
					(size 1.27 1.27)
				)
			)
		)
		(property "Value" "130R3F-GP"
			(at -0.0254 -2.5146 0)
			(unlocked yes)
			(layer "F.Fab")
			(hide yes)
			(effects
				(font
					(size 1.016 1.016)
					(thickness 0.1524)
				)
			)
		)
		(property "Device Type" "R603H22"
			(at -0.0254 -4.0386 0)
			(unlocked yes)
			(layer "F.Fab")
			(hide yes)
			(effects
				(font
					(size 1.016 1.016)
					(thickness 0.1524)
				)
			)
		)
		(duplicate_pad_numbers_are_jumpers no)
		(fp_line
			(start -0.4826 0)
			(end -0.2032 0)
			(stroke
				(width 0.2032)
				(type default)
			)
			(layer "F.SilkS")
		)
		(fp_line
			(start 0.2032 0)
			(end 0.4826 0)
			(stroke
				(width 0.2032)
				(type default)
			)
			(layer "F.SilkS")
		)
		(fp_rect
			(start -0.5842 1.3335)
			(end 0.5842 -1.3335)
			(stroke
				(width 0)
				(type default)
			)
			(fill no)
			(layer "F.CrtYd")
		)
		(fp_rect
			(start -0.5842 1.3335)
			(end 0.5842 -1.3335)
			(stroke
				(width 0)
				(type default)
			)
			(fill no)
			(layer "F.Fab")
		)
		(pad "1" smd custom
			(at 0 -0.762)
			(size 0.2159 0.2159)
			(layers "F.Cu" "F.Mask" "F.Paste")
			(net "P5V_A_3")
			(options
				(clearance outline)
				(anchor circle)
			)
			(primitives
				(gr_poly
					(pts
						(arc
							(start -0.3302 -0.4318)
							(mid -0.402042 -0.402042)
							(end -0.4318 -0.3302)
						)
						(arc
							(start -0.4318 0.3302)
							(mid -0.402042 0.402042)
							(end -0.3302 0.4318)
						)
						(arc
							(start 0.3302 0.4318)
							(mid 0.402042 0.402042)
							(end 0.4318 0.3302)
						)
						(arc
							(start 0.4318 -0.3302)
							(mid 0.402042 -0.402042)
							(end 0.3302 -0.4318)
						)
					)
					(width 0)
					(fill yes)
				)
			)
		)
		(pad "2" smd custom
			(at 0 0.762)
			(size 0.2159 0.2159)
			(layers "F.Cu" "F.Mask" "F.Paste")
			(net "FLT_HDD8")
			(options
				(clearance outline)
				(anchor circle)
			)
			(primitives
				(gr_poly
					(pts
						(arc
							(start -0.3302 -0.4318)
							(mid -0.402042 -0.402042)
							(end -0.4318 -0.3302)
						)
						(arc
							(start -0.4318 0.3302)
							(mid -0.402042 0.402042)
							(end -0.3302 0.4318)
						)
						(arc
							(start 0.3302 0.4318)
							(mid 0.402042 0.402042)
							(end 0.4318 0.3302)
						)
						(arc
							(start 0.4318 -0.3302)
							(mid 0.402042 -0.402042)
							(end 0.3302 -0.4318)
						)
					)
					(width 0)
					(fill yes)
				)
			)
		)
	)
)
